(kicad_pcb
	(version 20260206)
	(generator "pcbnew")
	(generator_version "10.0")
	(general
		(thickness 1.6)
		(legacy_teardrops no)
	)
	(paper "A4")
	(title_block
		(title "12092022_DA0F0TMDCD0_F0T_Management_Board_D_brd_V3_OCP.brd")
		(comment 1 "Grand Teton / footprints 395-400 of 1440")
	)
	(layers
		(0 "F.Cu" signal "TOP")
		(4 "In1.Cu" signal "GND")
		(6 "In2.Cu" signal "IN1")
		(8 "In3.Cu" signal "GND1")
		(10 "In4.Cu" signal "IN2")
		(12 "In5.Cu" signal "VCC")
		(14 "In6.Cu" signal "VCC1")
		(16 "In7.Cu" signal "IN3")
		(18 "In8.Cu" signal "GND2")
		(20 "In9.Cu" signal "IN4")
		(22 "In10.Cu" signal "GND3")
		(2 "B.Cu" signal "BOTTOM")
		(9 "F.Adhes" user "F.Adhesive")
		(11 "B.Adhes" user "B.Adhesive")
		(13 "F.Paste" user "Package Geometry/Pastemask Top")
		(15 "B.Paste" user "Package Geometry/Pastemask Bottom")
		(5 "F.SilkS" user "Ref Des/Silkscreen Top")
		(7 "B.SilkS" user "Ref Des/Silkscreen Bottom")
		(1 "F.Mask" user "Board Geometry/Soldermask Top")
		(3 "B.Mask" user "Board Geometry/Soldermask Bottom")
		(17 "Dwgs.User" user "User.Drawings")
		(19 "Cmts.User" user "User.Comments")
		(21 "Eco1.User" user "User.Eco1")
		(23 "Eco2.User" user "User.Eco2")
		(25 "Edge.Cuts" user "Board Geometry/Outline")
		(27 "Margin" user)
		(31 "F.CrtYd" user "Package Geometry/Place Bound Top")
		(29 "B.CrtYd" user "Package Geometry/Place Bound Bottom")
		(35 "F.Fab" user "Ref Des/Assembly Top")
		(33 "B.Fab" user "Ref Des/Assembly Bottom")
	)
	(footprint ""
		(layer "F.Cu")
		(at 39.5732 -49.7078)
		(property "Reference" "R400"
			(at 0 0 0)
			(layer "F.SilkS")
			(hide yes)
			(effects
				(font
					(size 1.27 1.27)
				)
			)
		)
		(property "Value" ""
			(at 0 0 0)
			(layer "F.Fab")
			(effects
				(font
					(size 1.27 1.27)
				)
			)
		)
		(duplicate_pad_numbers_are_jumpers no)
		(fp_line
			(start -0.7874 -0.4064)
			(end 0.7874 -0.4064)
			(stroke
				(width 0.1524)
				(type default)
			)
			(layer "F.SilkS")
		)
		(fp_line
			(start -0.7874 0.4064)
			(end -0.7874 -0.4064)
			(stroke
				(width 0.1524)
				(type default)
			)
			(layer "F.SilkS")
		)
		(fp_line
			(start 0.7874 -0.4064)
			(end 0.7874 0.4064)
			(stroke
				(width 0.1524)
				(type default)
			)
			(layer "F.SilkS")
		)
		(fp_line
			(start 0.7874 0.4064)
			(end -0.7874 0.4064)
			(stroke
				(width 0.1524)
				(type default)
			)
			(layer "F.SilkS")
		)
		(fp_line
			(start -0.67945 -0.305054)
			(end -0.12065 -0.305054)
			(stroke
				(width 0.1)
				(type default)
			)
			(layer "F.Fab")
		)
		(fp_line
			(start -0.67945 0.3048)
			(end -0.67945 -0.305054)
			(stroke
				(width 0.1)
				(type default)
			)
			(layer "F.Fab")
		)
		(fp_line
			(start -0.12065 -0.305054)
			(end -0.12065 -0.2794)
			(stroke
				(width 0.1)
				(type default)
			)
			(layer "F.Fab")
		)
		(fp_line
			(start -0.12065 -0.2794)
			(end 0.12065 -0.2794)
			(stroke
				(width 0.1)
				(type default)
			)
			(layer "F.Fab")
		)
		(fp_line
			(start -0.12065 0.2794)
			(end -0.12065 0.3048)
			(stroke
				(width 0.1)
				(type default)
			)
			(layer "F.Fab")
		)
		(fp_line
			(start -0.12065 0.3048)
			(end -0.67945 0.3048)
			(stroke
				(width 0.1)
				(type default)
			)
			(layer "F.Fab")
		)
		(fp_line
			(start 0.120396 0.2794)
			(end -0.12065 0.2794)
			(stroke
				(width 0.1)
				(type default)
			)
			(layer "F.Fab")
		)
		(fp_line
			(start 0.120396 0.3048)
			(end 0.120396 0.2794)
			(stroke
				(width 0.1)
				(type default)
			)
			(layer "F.Fab")
		)
		(fp_line
			(start 0.12065 -0.3048)
			(end 0.67945 -0.3048)
			(stroke
				(width 0.1)
				(type default)
			)
			(layer "F.Fab")
		)
		(fp_line
			(start 0.12065 -0.2794)
			(end 0.12065 -0.3048)
			(stroke
				(width 0.1)
				(type default)
			)
			(layer "F.Fab")
		)
		(fp_line
			(start 0.67945 -0.3048)
			(end 0.67945 0.3048)
			(stroke
				(width 0.1)
				(type default)
			)
			(layer "F.Fab")
		)
		(fp_line
			(start 0.67945 0.3048)
			(end 0.120396 0.3048)
			(stroke
				(width 0.1)
				(type default)
			)
			(layer "F.Fab")
		)
		(pad "1" smd circle
			(at -0.40005 0)
			(size 0 0)
			(layers "F.Cu" "F.Mask" "F.Paste")
			(net "P3V3_AUX")
		)
		(pad "2" smd circle
			(at 0.40005 0)
			(size 0 0)
			(layers "F.Cu" "F.Mask" "F.Paste")
			(net "FM_THERMTRIP_DLY_LVC1_R_N")
		)
	)
	(footprint ""
		(layer "F.Cu")
		(at 33.7566 -46.4058 -90)
		(property "Reference" "R70"
			(at 0 0 270)
			(layer "F.SilkS")
			(hide yes)
			(effects
				(font
					(size 1.27 1.27)
				)
			)
		)
		(property "Value" ""
			(at 0 0 270)
			(layer "F.Fab")
			(effects
				(font
					(size 1.27 1.27)
				)
			)
		)
		(duplicate_pad_numbers_are_jumpers no)
		(fp_line
			(start -0.7874 0.4064)
			(end -0.7874 -0.4064)
			(stroke
				(width 0.1524)
				(type default)
			)
			(layer "F.SilkS")
		)
		(fp_line
			(start 0.7874 0.4064)
			(end -0.7874 0.4064)
			(stroke
				(width 0.1524)
				(type default)
			)
			(layer "F.SilkS")
		)
		(fp_line
			(start -0.7874 -0.4064)
			(end 0.7874 -0.4064)
			(stroke
				(width 0.1524)
				(type default)
			)
			(layer "F.SilkS")
		)
		(fp_line
			(start 0.7874 -0.4064)
			(end 0.7874 0.4064)
			(stroke
				(width 0.1524)
				(type default)
			)
			(layer "F.SilkS")
		)
		(fp_line
			(start -0.67945 0.3048)
			(end -0.67945 -0.305054)
			(stroke
				(width 0.1)
				(type default)
			)
			(layer "F.Fab")
		)
		(fp_line
			(start -0.12065 0.3048)
			(end -0.67945 0.3048)
			(stroke
				(width 0.1)
				(type default)
			)
			(layer "F.Fab")
		)
		(fp_line
			(start 0.120396 0.3048)
			(end 0.120396 0.2794)
			(stroke
				(width 0.1)
				(type default)
			)
			(layer "F.Fab")
		)
		(fp_line
			(start 0.67945 0.3048)
			(end 0.120396 0.3048)
			(stroke
				(width 0.1)
				(type default)
			)
			(layer "F.Fab")
		)
		(fp_line
			(start -0.12065 0.2794)
			(end -0.12065 0.3048)
			(stroke
				(width 0.1)
				(type default)
			)
			(layer "F.Fab")
		)
		(fp_line
			(start 0.120396 0.2794)
			(end -0.12065 0.2794)
			(stroke
				(width 0.1)
				(type default)
			)
			(layer "F.Fab")
		)
		(fp_line
			(start -0.12065 -0.2794)
			(end 0.12065 -0.2794)
			(stroke
				(width 0.1)
				(type default)
			)
			(layer "F.Fab")
		)
		(fp_line
			(start 0.12065 -0.2794)
			(end 0.12065 -0.3048)
			(stroke
				(width 0.1)
				(type default)
			)
			(layer "F.Fab")
		)
		(fp_line
			(start 0.12065 -0.3048)
			(end 0.67945 -0.3048)
			(stroke
				(width 0.1)
				(type default)
			)
			(layer "F.Fab")
		)
		(fp_line
			(start 0.67945 -0.3048)
			(end 0.67945 0.3048)
			(stroke
				(width 0.1)
				(type default)
			)
			(layer "F.Fab")
		)
		(fp_line
			(start -0.67945 -0.305054)
			(end -0.12065 -0.305054)
			(stroke
				(width 0.1)
				(type default)
			)
			(layer "F.Fab")
		)
		(fp_line
			(start -0.12065 -0.305054)
			(end -0.12065 -0.2794)
			(stroke
				(width 0.1)
				(type default)
			)
			(layer "F.Fab")
		)
		(pad "1" smd circle
			(at -0.40005 0 270)
			(size 0 0)
			(layers "F.Cu" "F.Mask" "F.Paste")
			(net "RST_PCA9548_SENSOR_R_N")
		)
		(pad "2" smd circle
			(at 0.40005 0 270)
			(size 0 0)
			(layers "F.Cu" "F.Mask" "F.Paste")
			(net "RST_PCA9548_SENSOR_N")
		)
	)
	(footprint ""
		(layer "F.Cu")
		(at 23.61946 -108.71708 180)
		(property "Reference" "C161"
			(at 0 0 180)
			(layer "F.SilkS")
			(hide yes)
			(effects
				(font
					(size 1.27 1.27)
				)
			)
		)
		(property "Value" ""
			(at 0 0 180)
			(layer "F.Fab")
			(effects
				(font
					(size 1.27 1.27)
				)
			)
		)
		(duplicate_pad_numbers_are_jumpers no)
		(fp_line
			(start 0.7874 0.4064)
			(end -0.7874 0.4064)
			(stroke
				(width 0.1524)
				(type default)
			)
			(layer "F.SilkS")
		)
		(fp_line
			(start 0.7874 -0.4064)
			(end 0.7874 0.4064)
			(stroke
				(width 0.1524)
				(type default)
			)
			(layer "F.SilkS")
		)
		(fp_line
			(start -0.7874 0.4064)
			(end -0.7874 -0.4064)
			(stroke
				(width 0.1524)
				(type default)
			)
			(layer "F.SilkS")
		)
		(fp_line
			(start -0.7874 -0.4064)
			(end 0.7874 -0.4064)
			(stroke
				(width 0.1524)
				(type default)
			)
			(layer "F.SilkS")
		)
		(fp_line
			(start 0.67945 0.3048)
			(end 0.120396 0.3048)
			(stroke
				(width 0.1)
				(type default)
			)
			(layer "F.Fab")
		)
		(fp_line
			(start 0.67945 -0.3048)
			(end 0.67945 0.3048)
			(stroke
				(width 0.1)
				(type default)
			)
			(layer "F.Fab")
		)
		(fp_line
			(start 0.12065 -0.2794)
			(end 0.12065 -0.3048)
			(stroke
				(width 0.1)
				(type default)
			)
			(layer "F.Fab")
		)
		(fp_line
			(start 0.12065 -0.3048)
			(end 0.67945 -0.3048)
			(stroke
				(width 0.1)
				(type default)
			)
			(layer "F.Fab")
		)
		(fp_line
			(start 0.120396 0.3048)
			(end 0.120396 0.2794)
			(stroke
				(width 0.1)
				(type default)
			)
			(layer "F.Fab")
		)
		(fp_line
			(start 0.120396 0.2794)
			(end -0.12065 0.2794)
			(stroke
				(width 0.1)
				(type default)
			)
			(layer "F.Fab")
		)
		(fp_line
			(start -0.12065 0.3048)
			(end -0.67945 0.3048)
			(stroke
				(width 0.1)
				(type default)
			)
			(layer "F.Fab")
		)
		(fp_line
			(start -0.12065 0.2794)
			(end -0.12065 0.3048)
			(stroke
				(width 0.1)
				(type default)
			)
			(layer "F.Fab")
		)
		(fp_line
			(start -0.12065 -0.2794)
			(end 0.12065 -0.2794)
			(stroke
				(width 0.1)
				(type default)
			)
			(layer "F.Fab")
		)
		(fp_line
			(start -0.12065 -0.305054)
			(end -0.12065 -0.2794)
			(stroke
				(width 0.1)
				(type default)
			)
			(layer "F.Fab")
		)
		(fp_line
			(start -0.67945 0.3048)
			(end -0.67945 -0.305054)
			(stroke
				(width 0.1)
				(type default)
			)
			(layer "F.Fab")
		)
		(fp_line
			(start -0.67945 -0.305054)
			(end -0.12065 -0.305054)
			(stroke
				(width 0.1)
				(type default)
			)
			(layer "F.Fab")
		)
		(pad "1" smd circle
			(at -0.40005 0 180)
			(size 0 0)
			(layers "F.Cu" "F.Mask" "F.Paste")
			(net "RST_BMC_SELF_HW_D")
		)
		(pad "2" smd circle
			(at 0.40005 0 180)
			(size 0 0)
			(layers "F.Cu" "F.Mask" "F.Paste")
			(net "RST_BMC_SELF_HW_D_C")
		)
	)
	(footprint ""
		(layer "F.Cu")
		(at 30.2514 -101.0412 -90)
		(property "Reference" "R769"
			(at 0 0 270)
			(layer "F.SilkS")
			(hide yes)
			(effects
				(font
					(size 1.27 1.27)
				)
			)
		)
		(property "Value" ""
			(at 0 0 270)
			(layer "F.Fab")
			(effects
				(font
					(size 1.27 1.27)
				)
			)
		)
		(duplicate_pad_numbers_are_jumpers no)
		(fp_line
			(start -0.7874 0.4064)
			(end -0.7874 -0.4064)
			(stroke
				(width 0.1524)
				(type default)
			)
			(layer "F.SilkS")
		)
		(fp_line
			(start 0.7874 0.4064)
			(end -0.7874 0.4064)
			(stroke
				(width 0.1524)
				(type default)
			)
			(layer "F.SilkS")
		)
		(fp_line
			(start -0.7874 -0.4064)
			(end 0.7874 -0.4064)
			(stroke
				(width 0.1524)
				(type default)
			)
			(layer "F.SilkS")
		)
		(fp_line
			(start 0.7874 -0.4064)
			(end 0.7874 0.4064)
			(stroke
				(width 0.1524)
				(type default)
			)
			(layer "F.SilkS")
		)
		(fp_line
			(start -0.67945 0.3048)
			(end -0.67945 -0.305054)
			(stroke
				(width 0.1)
				(type default)
			)
			(layer "F.Fab")
		)
		(fp_line
			(start -0.12065 0.3048)
			(end -0.67945 0.3048)
			(stroke
				(width 0.1)
				(type default)
			)
			(layer "F.Fab")
		)
		(fp_line
			(start 0.120396 0.3048)
			(end 0.120396 0.2794)
			(stroke
				(width 0.1)
				(type default)
			)
			(layer "F.Fab")
		)
		(fp_line
			(start 0.67945 0.3048)
			(end 0.120396 0.3048)
			(stroke
				(width 0.1)
				(type default)
			)
			(layer "F.Fab")
		)
		(fp_line
			(start -0.12065 0.2794)
			(end -0.12065 0.3048)
			(stroke
				(width 0.1)
				(type default)
			)
			(layer "F.Fab")
		)
		(fp_line
			(start 0.120396 0.2794)
			(end -0.12065 0.2794)
			(stroke
				(width 0.1)
				(type default)
			)
			(layer "F.Fab")
		)
		(fp_line
			(start -0.12065 -0.2794)
			(end 0.12065 -0.2794)
			(stroke
				(width 0.1)
				(type default)
			)
			(layer "F.Fab")
		)
		(fp_line
			(start 0.12065 -0.2794)
			(end 0.12065 -0.3048)
			(stroke
				(width 0.1)
				(type default)
			)
			(layer "F.Fab")
		)
		(fp_line
			(start 0.12065 -0.3048)
			(end 0.67945 -0.3048)
			(stroke
				(width 0.1)
				(type default)
			)
			(layer "F.Fab")
		)
		(fp_line
			(start 0.67945 -0.3048)
			(end 0.67945 0.3048)
			(stroke
				(width 0.1)
				(type default)
			)
			(layer "F.Fab")
		)
		(fp_line
			(start -0.67945 -0.305054)
			(end -0.12065 -0.305054)
			(stroke
				(width 0.1)
				(type default)
			)
			(layer "F.Fab")
		)
		(fp_line
			(start -0.12065 -0.305054)
			(end -0.12065 -0.2794)
			(stroke
				(width 0.1)
				(type default)
			)
			(layer "F.Fab")
		)
		(pad "1" smd circle
			(at -0.40005 0 270)
			(size 0 0)
			(layers "F.Cu" "F.Mask" "F.Paste")
			(net "FM_THROTTLE_N")
		)
		(pad "2" smd circle
			(at 0.40005 0 270)
			(size 0 0)
			(layers "F.Cu" "F.Mask" "F.Paste")
			(net "FM_THROTTLE_R_N")
		)
	)
	(footprint ""
		(layer "F.Cu")
		(at 7.28091 -62.512702 180)
		(property "Reference" "PC223"
			(at 0 0 180)
			(layer "F.SilkS")
			(hide yes)
			(effects
				(font
					(size 1.27 1.27)
				)
			)
		)
		(property "Value" ""
			(at 0 0 180)
			(layer "F.Fab")
			(effects
				(font
					(size 1.27 1.27)
				)
			)
		)
		(duplicate_pad_numbers_are_jumpers no)
		(fp_line
			(start 0.7874 0.4064)
			(end -0.7874 0.4064)
			(stroke
				(width 0.1524)
				(type default)
			)
			(layer "F.SilkS")
		)
		(fp_line
			(start 0.7874 -0.4064)
			(end 0.7874 0.4064)
			(stroke
				(width 0.1524)
				(type default)
			)
			(layer "F.SilkS")
		)
		(fp_line
			(start -0.7874 0.4064)
			(end -0.7874 -0.4064)
			(stroke
				(width 0.1524)
				(type default)
			)
			(layer "F.SilkS")
		)
		(fp_line
			(start -0.7874 -0.4064)
			(end 0.7874 -0.4064)
			(stroke
				(width 0.1524)
				(type default)
			)
			(layer "F.SilkS")
		)
		(fp_line
			(start 0.67945 0.3048)
			(end 0.120396 0.3048)
			(stroke
				(width 0.1)
				(type default)
			)
			(layer "F.Fab")
		)
		(fp_line
			(start 0.67945 -0.3048)
			(end 0.67945 0.3048)
			(stroke
				(width 0.1)
				(type default)
			)
			(layer "F.Fab")
		)
		(fp_line
			(start 0.12065 -0.2794)
			(end 0.12065 -0.3048)
			(stroke
				(width 0.1)
				(type default)
			)
			(layer "F.Fab")
		)
		(fp_line
			(start 0.12065 -0.3048)
			(end 0.67945 -0.3048)
			(stroke
				(width 0.1)
				(type default)
			)
			(layer "F.Fab")
		)
		(fp_line
			(start 0.120396 0.3048)
			(end 0.120396 0.2794)
			(stroke
				(width 0.1)
				(type default)
			)
			(layer "F.Fab")
		)
		(fp_line
			(start 0.120396 0.2794)
			(end -0.12065 0.2794)
			(stroke
				(width 0.1)
				(type default)
			)
			(layer "F.Fab")
		)
		(fp_line
			(start -0.12065 0.3048)
			(end -0.67945 0.3048)
			(stroke
				(width 0.1)
				(type default)
			)
			(layer "F.Fab")
		)
		(fp_line
			(start -0.12065 0.2794)
			(end -0.12065 0.3048)
			(stroke
				(width 0.1)
				(type default)
			)
			(layer "F.Fab")
		)
		(fp_line
			(start -0.12065 -0.2794)
			(end 0.12065 -0.2794)
			(stroke
				(width 0.1)
				(type default)
			)
			(layer "F.Fab")
		)
		(fp_line
			(start -0.12065 -0.305054)
			(end -0.12065 -0.2794)
			(stroke
				(width 0.1)
				(type default)
			)
			(layer "F.Fab")
		)
		(fp_line
			(start -0.67945 0.3048)
			(end -0.67945 -0.305054)
			(stroke
				(width 0.1)
				(type default)
			)
			(layer "F.Fab")
		)
		(fp_line
			(start -0.67945 -0.305054)
			(end -0.12065 -0.305054)
			(stroke
				(width 0.1)
				(type default)
			)
			(layer "F.Fab")
		)
		(pad "1" smd circle
			(at -0.40005 0 180)
			(size 0 0)
			(layers "F.Cu" "F.Mask" "F.Paste")
			(net "SW_P3V3_AUX_FLT")
		)
		(pad "2" smd circle
			(at 0.40005 0 180)
			(size 0 0)
			(layers "F.Cu" "F.Mask" "F.Paste")
			(net "GND")
		)
	)
	(footprint ""
		(layer "F.Cu")
		(at 85.29955 -43.157394 180)
		(property "Reference" "R335"
			(at 0 0 180)
			(layer "F.SilkS")
			(hide yes)
			(effects
				(font
					(size 1.27 1.27)
				)
			)
		)
		(property "Value" ""
			(at 0 0 180)
			(layer "F.Fab")
			(effects
				(font
					(size 1.27 1.27)
				)
			)
		)
		(duplicate_pad_numbers_are_jumpers no)
		(fp_line
			(start 0.7874 0.4064)
			(end -0.7874 0.4064)
			(stroke
				(width 0.1524)
				(type default)
			)
			(layer "F.SilkS")
		)
		(fp_line
			(start 0.7874 -0.4064)
			(end 0.7874 0.4064)
			(stroke
				(width 0.1524)
				(type default)
			)
			(layer "F.SilkS")
		)
		(fp_line
			(start -0.7874 0.4064)
			(end -0.7874 -0.4064)
			(stroke
				(width 0.1524)
				(type default)
			)
			(layer "F.SilkS")
		)
		(fp_line
			(start -0.7874 -0.4064)
			(end 0.7874 -0.4064)
			(stroke
				(width 0.1524)
				(type default)
			)
			(layer "F.SilkS")
		)
		(fp_line
			(start 0.67945 0.3048)
			(end 0.120396 0.3048)
			(stroke
				(width 0.1)
				(type default)
			)
			(layer "F.Fab")
		)
		(fp_line
			(start 0.67945 -0.3048)
			(end 0.67945 0.3048)
			(stroke
				(width 0.1)
				(type default)
			)
			(layer "F.Fab")
		)
		(fp_line
			(start 0.12065 -0.2794)
			(end 0.12065 -0.3048)
			(stroke
				(width 0.1)
				(type default)
			)
			(layer "F.Fab")
		)
		(fp_line
			(start 0.12065 -0.3048)
			(end 0.67945 -0.3048)
			(stroke
				(width 0.1)
				(type default)
			)
			(layer "F.Fab")
		)
		(fp_line
			(start 0.120396 0.3048)
			(end 0.120396 0.2794)
			(stroke
				(width 0.1)
				(type default)
			)
			(layer "F.Fab")
		)
		(fp_line
			(start 0.120396 0.2794)
			(end -0.12065 0.2794)
			(stroke
				(width 0.1)
				(type default)
			)
			(layer "F.Fab")
		)
		(fp_line
			(start -0.12065 0.3048)
			(end -0.67945 0.3048)
			(stroke
				(width 0.1)
				(type default)
			)
			(layer "F.Fab")
		)
		(fp_line
			(start -0.12065 0.2794)
			(end -0.12065 0.3048)
			(stroke
				(width 0.1)
				(type default)
			)
			(layer "F.Fab")
		)
		(fp_line
			(start -0.12065 -0.2794)
			(end 0.12065 -0.2794)
			(stroke
				(width 0.1)
				(type default)
			)
			(layer "F.Fab")
		)
		(fp_line
			(start -0.12065 -0.305054)
			(end -0.12065 -0.2794)
			(stroke
				(width 0.1)
				(type default)
			)
			(layer "F.Fab")
		)
		(fp_line
			(start -0.67945 0.3048)
			(end -0.67945 -0.305054)
			(stroke
				(width 0.1)
				(type default)
			)
			(layer "F.Fab")
		)
		(fp_line
			(start -0.67945 -0.305054)
			(end -0.12065 -0.305054)
			(stroke
				(width 0.1)
				(type default)
			)
			(layer "F.Fab")
		)
		(pad "1" smd circle
			(at -0.40005 0 180)
			(size 0 0)
			(layers "F.Cu" "F.Mask" "F.Paste")
			(net "GND")
		)
		(pad "2" smd circle
			(at 0.40005 0 180)
			(size 0 0)
			(layers "F.Cu" "F.Mask" "F.Paste")
			(net "M_BMC_DDR4_MA<9>")
		)
	)
)
